# S9S_MB_2U (Grand Teton) — schematic netlist excerpt (pin names and nets, part order shuffled) for the footprints in the layout excerpt that follows; sources: Cadence DE-HDL packaged netlist, KiCad conversion of 03242023_DA0F0TMBIJ0_F0T_Motherboard_J_brd_V01_OCP.brd

R1478  Q_RES  10K 1% CHIP  pkg 0402LF  page 200 : A = FM_PCH_XTAL_INPUT_MODE_MGPIO_TE ; B = GND
R4057  Q_RES  33.2 1% CHIP  pkg 0402LF  page 215 : A = PRSNT_SWB_ISO_N ; B = PRSNT_SWB_ISO_R_N

(kicad_pcb
	(version 20260206)
	(generator "pcbnew")
	(generator_version "10.0")
	(general
		(thickness 1.6)
		(legacy_teardrops no)
	)
	(paper "A4")
	(title_block
		(title "03242023_DA0F0TMBIJ0_F0T_Motherboard_J_brd_V01_OCP.brd")
		(comment 1 "Grand Teton / footprints 668-669 of 6105")
	)
	(layers
		(0 "F.Cu" signal "TOP")
		(4 "In1.Cu" signal "GND")
		(6 "In2.Cu" signal "IN1")
		(8 "In3.Cu" signal "GND1")
		(10 "In4.Cu" signal "IN2")
		(12 "In5.Cu" signal "GND2")
		(14 "In6.Cu" signal "IN3")
		(16 "In7.Cu" signal "GND3")
		(18 "In8.Cu" signal "VCC")
		(20 "In9.Cu" signal "VCC1")
		(22 "In10.Cu" signal "GND4")
		(24 "In11.Cu" signal "IN4")
		(26 "In12.Cu" signal "GND5")
		(28 "In13.Cu" signal "IN5")
		(30 "In14.Cu" signal "GND6")
		(32 "In15.Cu" signal "IN6")
		(34 "In16.Cu" signal "GND7")
		(2 "B.Cu" signal "BOTTOM")
		(9 "F.Adhes" user "F.Adhesive")
		(11 "B.Adhes" user "B.Adhesive")
		(13 "F.Paste" user "Package Geometry/Pastemask Top")
		(15 "B.Paste" user "Package Geometry/Pastemask Bottom")
		(5 "F.SilkS" user "Ref Des/Silkscreen Top")
		(7 "B.SilkS" user "Ref Des/Silkscreen Bottom")
		(1 "F.Mask" user "Board Geometry/Soldermask Top")
		(3 "B.Mask" user "Board Geometry/Soldermask Bottom")
		(17 "Dwgs.User" user "User.Drawings")
		(19 "Cmts.User" user "User.Comments")
		(21 "Eco1.User" user "User.Eco1")
		(23 "Eco2.User" user "User.Eco2")
		(25 "Edge.Cuts" user "Board Geometry/Outline")
		(27 "Margin" user)
		(31 "F.CrtYd" user "Package Geometry/Place Bound Top")
		(29 "B.CrtYd" user "Package Geometry/Place Bound Bottom")
		(35 "F.Fab" user "Ref Des/Assembly Top")
		(33 "B.Fab" user "Ref Des/Assembly Bottom")
	)
	(footprint ""
		(layer "F.Cu")
		(at 317.396622 -60.315348 180)
		(property "Reference" "R1478"
			(at 0 0 180)
			(layer "F.SilkS")
			(hide yes)
			(effects
				(font
					(size 1.27 1.27)
				)
			)
		)
		(property "Value" ""
			(at 0 0 180)
			(layer "F.Fab")
			(effects
				(font
					(size 1.27 1.27)
				)
			)
		)
		(duplicate_pad_numbers_are_jumpers no)
		(fp_line
			(start 0.7874 0.4064)
			(end -0.7874 0.4064)
			(stroke
				(width 0.1524)
				(type default)
			)
			(layer "F.SilkS")
		)
		(fp_line
			(start 0.7874 -0.4064)
			(end 0.7874 0.4064)
			(stroke
				(width 0.1524)
				(type default)
			)
			(layer "F.SilkS")
		)
		(fp_line
			(start -0.7874 0.4064)
			(end -0.7874 -0.4064)
			(stroke
				(width 0.1524)
				(type default)
			)
			(layer "F.SilkS")
		)
		(fp_line
			(start -0.7874 -0.4064)
			(end 0.7874 -0.4064)
			(stroke
				(width 0.1524)
				(type default)
			)
			(layer "F.SilkS")
		)
		(fp_line
			(start 0.67945 0.3048)
			(end 0.120396 0.3048)
			(stroke
				(width 0.1)
				(type default)
			)
			(layer "F.Fab")
		)
		(fp_line
			(start 0.67945 -0.3048)
			(end 0.67945 0.3048)
			(stroke
				(width 0.1)
				(type default)
			)
			(layer "F.Fab")
		)
		(fp_line
			(start 0.12065 -0.2794)
			(end 0.12065 -0.3048)
			(stroke
				(width 0.1)
				(type default)
			)
			(layer "F.Fab")
		)
		(fp_line
			(start 0.12065 -0.3048)
			(end 0.67945 -0.3048)
			(stroke
				(width 0.1)
				(type default)
			)
			(layer "F.Fab")
		)
		(fp_line
			(start 0.120396 0.3048)
			(end 0.120396 0.2794)
			(stroke
				(width 0.1)
				(type default)
			)
			(layer "F.Fab")
		)
		(fp_line
			(start 0.120396 0.2794)
			(end -0.12065 0.2794)
			(stroke
				(width 0.1)
				(type default)
			)
			(layer "F.Fab")
		)
		(fp_line
			(start -0.12065 0.3048)
			(end -0.67945 0.3048)
			(stroke
				(width 0.1)
				(type default)
			)
			(layer "F.Fab")
		)
		(fp_line
			(start -0.12065 0.2794)
			(end -0.12065 0.3048)
			(stroke
				(width 0.1)
				(type default)
			)
			(layer "F.Fab")
		)
		(fp_line
			(start -0.12065 -0.2794)
			(end 0.12065 -0.2794)
			(stroke
				(width 0.1)
				(type default)
			)
			(layer "F.Fab")
		)
		(fp_line
			(start -0.12065 -0.305054)
			(end -0.12065 -0.2794)
			(stroke
				(width 0.1)
				(type default)
			)
			(layer "F.Fab")
		)
		(fp_line
			(start -0.67945 0.3048)
			(end -0.67945 -0.305054)
			(stroke
				(width 0.1)
				(type default)
			)
			(layer "F.Fab")
		)
		(fp_line
			(start -0.67945 -0.305054)
			(end -0.12065 -0.305054)
			(stroke
				(width 0.1)
				(type default)
			)
			(layer "F.Fab")
		)
		(pad "1" smd circle
			(at -0.40005 0 180)
			(size 0 0)
			(layers "F.Cu" "F.Mask" "F.Paste")
			(net "FM_PCH_XTAL_INPUT_MODE_MGPIO_TE")
		)
		(pad "2" smd circle
			(at 0.40005 0 180)
			(size 0 0)
			(layers "F.Cu" "F.Mask" "F.Paste")
			(net "GND")
		)
	)
	(footprint ""
		(layer "F.Cu")
		(at 186.733942 -133.689598 -90)
		(property "Reference" "R4057"
			(at 0 0 270)
			(layer "F.SilkS")
			(hide yes)
			(effects
				(font
					(size 1.27 1.27)
				)
			)
		)
		(property "Value" ""
			(at 0 0 270)
			(layer "F.Fab")
			(effects
				(font
					(size 1.27 1.27)
				)
			)
		)
		(duplicate_pad_numbers_are_jumpers no)
		(fp_line
			(start -0.7874 0.4064)
			(end -0.7874 -0.4064)
			(stroke
				(width 0.1524)
				(type default)
			)
			(layer "F.SilkS")
		)
		(fp_line
			(start 0.7874 0.4064)
			(end -0.7874 0.4064)
			(stroke
				(width 0.1524)
				(type default)
			)
			(layer "F.SilkS")
		)
		(fp_line
			(start -0.7874 -0.4064)
			(end 0.7874 -0.4064)
			(stroke
				(width 0.1524)
				(type default)
			)
			(layer "F.SilkS")
		)
		(fp_line
			(start 0.7874 -0.4064)
			(end 0.7874 0.4064)
			(stroke
				(width 0.1524)
				(type default)
			)
			(layer "F.SilkS")
		)
		(fp_line
			(start -0.67945 0.3048)
			(end -0.67945 -0.305054)
			(stroke
				(width 0.1)
				(type default)
			)
			(layer "F.Fab")
		)
		(fp_line
			(start -0.12065 0.3048)
			(end -0.67945 0.3048)
			(stroke
				(width 0.1)
				(type default)
			)
			(layer "F.Fab")
		)
		(fp_line
			(start 0.120396 0.3048)
			(end 0.120396 0.2794)
			(stroke
				(width 0.1)
				(type default)
			)
			(layer "F.Fab")
		)
		(fp_line
			(start 0.67945 0.3048)
			(end 0.120396 0.3048)
			(stroke
				(width 0.1)
				(type default)
			)
			(layer "F.Fab")
		)
		(fp_line
			(start -0.12065 0.2794)
			(end -0.12065 0.3048)
			(stroke
				(width 0.1)
				(type default)
			)
			(layer "F.Fab")
		)
		(fp_line
			(start 0.120396 0.2794)
			(end -0.12065 0.2794)
			(stroke
				(width 0.1)
				(type default)
			)
			(layer "F.Fab")
		)
		(fp_line
			(start -0.12065 -0.2794)
			(end 0.12065 -0.2794)
			(stroke
				(width 0.1)
				(type default)
			)
			(layer "F.Fab")
		)
		(fp_line
			(start 0.12065 -0.2794)
			(end 0.12065 -0.3048)
			(stroke
				(width 0.1)
				(type default)
			)
			(layer "F.Fab")
		)
		(fp_line
			(start 0.12065 -0.3048)
			(end 0.67945 -0.3048)
			(stroke
				(width 0.1)
				(type default)
			)
			(layer "F.Fab")
		)
		(fp_line
			(start 0.67945 -0.3048)
			(end 0.67945 0.3048)
			(stroke
				(width 0.1)
				(type default)
			)
			(layer "F.Fab")
		)
		(fp_line
			(start -0.67945 -0.305054)
			(end -0.12065 -0.305054)
			(stroke
				(width 0.1)
				(type default)
			)
			(layer "F.Fab")
		)
		(fp_line
			(start -0.12065 -0.305054)
			(end -0.12065 -0.2794)
			(stroke
				(width 0.1)
				(type default)
			)
			(layer "F.Fab")
		)
		(pad "1" smd circle
			(at -0.40005 0 270)
			(size 0 0)
			(layers "F.Cu" "F.Mask" "F.Paste")
			(net "PRSNT_SWB_ISO_N")
		)
		(pad "2" smd circle
			(at 0.40005 0 270)
			(size 0 0)
			(layers "F.Cu" "F.Mask" "F.Paste")
			(net "PRSNT_SWB_ISO_R_N")
		)
	)
)
